FILE_TYPE = CONNECTIVITY;
{Allegro Design Entry HDL 16.6-p007 (v16-6-112F) 10/10/2012}
"PAGE_NUMBER" = 190;
0"NC";
1"RST_CPU0_LVC3_N";
2"RST_CPU1_LVC3_N";
3"FM_PVCCMCP_CPU0_EN";
4"RST_CPU1_LVC3_R1_N";
5"RST_CPU0_LVC3_R1_N";
6"FM_PCH_PLD_DATA";
7"RST_CD_CPU0_POR_N";
8"PWRGD_PVCCIN_CPU1";
9"RST_PCIE_RISER1_PERST_N";
10"PWRGD_CPU0_LVC3";
11"PWRGD_PVSA_CPU0";
12"SGPIO_BMC_DOUT";
13"FM_PVCCIOMCP_CPU0_EN";
14"SGPIO_BMC_CLK";
15"FM_SLPS3_N";
16"PWRGD_P3V3";
17"FM_CPU0_FIVR_FAULT_LVT3_N";
18"FM_CPU0_PKGID1";
19"FM_CPU0_PKGID2";
20"FM_DEBUG_RST_BTN_N";
21"FM_CPU0_PROC_ID0";
22"FM_CPU0_PROC_ID1";
23"FM_PWR_BTN_N";
24"CLK_32K_SUSCLK_PLD";
25"FM_CPU0_PKGID0";
26"FM_CPU_CATERR_DLY_LVT3_N";
27"RST_PCIE_PCH_PERST_N";
28"PU_RST_PERST_BIT0";
29"PWRGD_P5V";
30"RST_PCIE_CPU_DEV1_N";
31"RST_PCIE_CPU_DEV2_N";
32"RST_PCIE_CPU_DEV3_N";
33"FM_BMC_CPLD_GPO";
34"FM_MP_PS_FAIL_N";
35"PWRGD_PVPP_GHJ";
36"PWRGD_PVPP_KLM";
37"CLK_25M_CPLD";
38"PWRGD_PVCCIN_CPU0";
39"PWRGD_PVCCMCP_CPU1";
40"SGPIO_BMC_LD_N";
41"SMB_SLOTX24_PCH_STBY_LVC3_SCL";
42"SMB_SLOTX24_PCH_STBY_LVC3_SDA";
43"SP1_BMC_HOST_UART_RX";
44"SP1_BMC_HOST_UART_TX";
45"UART_BMC_RXD5";
46"UART_BMC_TXD5";
47"FM_UART_ALERT_N";
48"FM_GLOBAL_RST_WARN_N";
49"FM_MEM_EVENT_FUNC";
50"RST_RSMRST_DLY";
51"RST_RSMRST_R_N";
52"TP_CPLD1_PL11A";
53"TP_CPLD1_PL7D_PCLKT4_0";
54"TP_CPLD1_PL2B_L_GPLLC_IN";
55"TP_CPLD1_PL1B_L_GPLLC_FB";
56"TP_CPLD1_PL1A_L_GPLLT_FB";
57"RST_RSMRST_R_N";
58"RST_RSMRST_N";
59"TP_CPLD1_PB25B_SI_SISPI";
60"TP_CPLD1_PB16B_PCLKC2_1";
61"TP_CPLD1_PB16A_PCLKT2_1";
62"TP_CPLD1_PB11B_PCLKC2_0";
63"TP_CPLD1_PB8D";
64"TP_CPLD1_PB8B_SO_SPISO";
65"TP_CPLD1_PB8A_MCLK_CCLK";
66"TP_CPLD1_PB5A_CSSPIN";
67"FM_ADR_MODE_SEL";
68"RST_PCIE_M2_DEV_N";
69"PWRGD_PVTT_CPU1";
70"PWRGD_PVNN_P1V05_PCH";
71"RST_CD_CPU1_POR_N";
72"RST_CPU1_LVC3_R1_N";
73"FM_CPU1_PKGID2";
74"PWRGD_CPU1_LVC3";
75"FM_DB1200ZL_BCLKS_EN_N";
76"FM_CPU0_SKTOCC_LVT3_N";
77"FM_CPU1_PKGID1";
78"FM_CPU_CATERR_LVT3_N";
79"PWRGD_DRAMPWRGD";
80"FM_CPU1_PKGID0";
81"FM_CPU1_SKTOCC_LVT3_N";
82"XDP_SYSPWROK";
83"XDP_PWRGD_RST_N";
84"RST_CPU0_LVC3_R1_N";
85"FM_PVCCMCP_CPU1_EN";
86"FM_PVCCIO_CPU1_EN";
87"FM_PVCCIO_CPU0_EN";
88"FM_PVCCIOMCP_CPU1_EN";
89"PWRGD_PVCCIOMCP_CPU0";
90"PWRGD_PVCCIOMCP_CPU1";
91"PWRGD_PVCCMCP_CPU0";
92"PWRGD_PVSA_CPU1";
93"FM_UARTSW_MSB_N";
94"FM_UARTSW_LSB_N";
95"FM_IE_DISABLE_N";
96"FM_156M_CPU1_BRD_OSC_EN";
97"FM_156M_CPU0_BRD_OSC_EN";
98"FM_CPLD_BMC_PWRDN_N";
99"FM_SOL_UART_CH_SEL";
100"FM_CPLD_DBG_PWR_EN_N";
101"FM_CPLD_UART_CH_LOCK_N";
102"PWRGD_PVCCIO_CPU0";
103"PWRGD_PVPP_ABC";
104"FM_BMC_CPLD_MP_RST_N";
105"PWRGD_PVPP_DEF";
106"FM_CPU_MSMI_LVT3_N";
107"FM_CPU0_VRM_OSC_EN";
108"FM_CPU1_RC_EN";
109"FM_CPU0_RC_EN";
110"FM_DIS_ADR_DLY";
%"RES"
"1","(-4150,5200)","0","mstr_discrete","I116";
;
CDS_SEC"1"
ROOM"CPLD"
CDS_LOCATION"R3P34"
SEC"1"
BOM_COST"CPLD"
CDS_LIB"mstr_discrete"
SEC_TYPE"0402"
LOCATION"R3P34"
PART_NUMBER"G21497-005"
VALUE"0.0"
TOLERANCE"5%"
PACK_TYPE"0402"
MATERIAL"CHIP"
WATTAGE"1/16W";
"B"
$PN"2"1;
"A"
$PN"1"5;
%"RES"
"1","(-4150,5000)","0","mstr_discrete","I117";
;
CDS_SEC"1"
ROOM"CPLD"
CDS_LOCATION"R3P35"
SEC"1"
CDS_LIB"mstr_discrete"
BOM_COST"CPLD"
SEC_TYPE"0402"
MATERIAL"CHIP"
LOCATION"R3P35"
PART_NUMBER"G21497-005"
VALUE"0.0"
TOLERANCE"5%"
PACK_TYPE"0402"
WATTAGE"1/16W";
"B"
$PN"2"2;
"A"
$PN"1"4;
%"LCMXO2_A"
"4","(-1950,2950)","0","mstr_memory","I179";
;
CDS_SEC"1"
PACK_TYPE"256BGA"
ROOM"CPLD"
SEC_TYPE"256BGA"
SEC"1"
CDS_LIB"mstr_memory"
CDS_LMAN_SYM_OUTLINE"-550,1750,550,-1750"
CDS_LOCATION"U8D7"
BOM_COST"CPLD"
LOCATION"U8D7"
PART_NUMBER"H63395-001"
MATERIAL"IC";
"PL7C_PCLKT4_0"
$PN"J1"14;
"PB19A"
$PN"P10"71;
"PB18D"
$PN"L10"99;
"PB18C"
$PN"M9"101;
"PL5D"
$PN"H6"16;
"PB3A"
$PN"P4"108;
"PB3B"
$PN"T4"92;
"PB3C"
$PN"T2"67;
"PB3D"
$PN"R3"109;
"PB5A_CSSPIN"
$PN"R5"66;
"PB5B"
$PN"P5"91;
"PB6A"
$PN"T5"90;
"PB6B"
$PN"R6"68;
"PB6C"
$PN"T3"110;
"PB6D"
$PN"R4"104;
"PB8A_MCLK_CCLK"
$PN"P6"65;
"PB8B_SO_SPISO"
$PN"T6"64;
"PB8C"
$PN"N6"89;
"PB8D"
$PN"L7"63;
"PB9A"
$PN"R7"69;
"PB9B"
$PN"P7"88;
"PB9C"
$PN"M7"87;
"PB9D"
$PN"N7"103;
"PB11A_PCLKT2_0"
$PN"T7"86;
"PB11B_PCLKC2_0"
$PN"R8"62;
"PB11C"
$PN"M6"105;
"PB11D"
$PN"L8"102;
"PB12A"
$PN"P8"70;
"PB12B"
$PN"T8"100;
"PB12C"
$PN"N8"96;
"PB12D"
$PN"L9"95;
"PB16A_PCLKT2_1"
$PN"T9"61;
"PB16B_PCLKC2_1"
$PN"P9"60;
"PB16C"
$PN"M8"85;
"PB16D"
$PN"N9"98;
"PB18A"
$PN"R9"94;
"PB18B"
$PN"T10"97;
"PB19B"
$PN"R10"84;
"PB19C"
$PN"N10"72;
"PB19D"
$PN"M11"83;
"PB21A"
$PN"T11"73;
"PB21B"
$PN"P11"93;
"PB21C"
$PN"M10"74;
"PB21D"
$PN"N11"82;
"PB22A"
$PN"R11"75;
"PB22B"
$PN"T12"81;
"PB22C"
$PN"R13"107;
"PB22D"
$PN"T14"76;
"PB24A"
$PN"P12"77;
"PB24B"
$PN"T13"106;
"PB25A_SN"
$PN"R12"80;
"PB25B_SI_SISPI"
$PN"P13"59;
"PB25C"
$PN"T15"79;
"PB25D"
$PN"R14"78;
"PL1A_L_GPLLT_FB"
$PN"D3"56;
"PL1B_L_GPLLC_FB"
$PN"D1"55;
"PL1C"
$PN"B1"27;
"PL1D"
$PN"C2"6;
"PL2A_L_GPLLT_IN"
$PN"E2"26;
"PL2B_L_GPLLC_IN"
$PN"E3"54;
"PL2C"
$PN"C1"30;
"PL2D"
$PN"D2"49;
"PL3A_PCLKT5_0"
$PN"E1"24;
"PL3B_PCLKC5_0"
$PN"F2"25;
"PL3C"
$PN"F4"28;
"PL3D"
$PN"G6"23;
"PL4A"
$PN"F3"22;
"PL4B"
$PN"F1"21;
"PL4C"
$PN"G5"20;
"PL4D"
$PN"G4"51;
"PL5A"
$PN"G2"19;
"PL5B"
$PN"G3"18;
"PL5C"
$PN"F5"17;
"PL6A"
$PN"G1"15;
"PL6B"
$PN"H2"3;
"PL6C"
$PN"H4"34;
"PL6D"
$PN"J6"29;
"PL7A"
$PN"H3"31;
"PL7B"
$PN"H1"32;
"PL7D_PCLKC4_0"
$PN"J3"53;
"PL9A"
$PN"J2"12;
"PL9B"
$PN"K1"13;
"PL9C"
$PN"H5"41;
"PL9D"
$PN"J4"42;
"PL10A"
$PN"K3"43;
"PL10B"
$PN"K2"44;
"PL10C"
$PN"J5"45;
"PL10D"
$PN"K6"46;
"PL11A"
$PN"L1"11;
"PL11B"
$PN"L3"52;
"PL11C"
$PN"K4"40;
"PL11D"
$PN"L5"10;
"PL12A_PCLKT3_0"
$PN"L2"37;
"PL12B_PCLKC3_0"
$PN"M1"50;
"PL12C"
$PN"K5"38;
"PL12D"
$PN"L4"39;
"PL13A"
$PN"M3"9;
"PL13B"
$PN"N1"8;
"PL13C"
$PN"N2"36;
"PL13D"
$PN"P1"48;
"PL14A"
$PN"M2"35;
"PL14B"
$PN"N3"7;
"PL14C"
$PN"R1"33;
"PL14D"
$PN"P2"47;
%"RES"
"1","(-1350,5200)","0","mstr_discrete","I338";
;
ROOM"CPLD"
CDS_LOCATION"R2R2"
$SEC"1"
CDS_SEC"1"
BOM_COST"CPLD"
CDS_LIB"mstr_discrete"
LOCATION"R2R2"
PART_NUMBER"G21796-074"
VALUE"33.2"
TOLERANCE"1%"
PACK_TYPE"0402"
MATERIAL"CHIP"
WATTAGE"1/16W";
"B"
$PN"2"58;
"A"
$PN"1"57;
END.
